#ISCELL
  mstr_symbols cad_note *
  *
#ISCELL
  mstr_symbols intel_corp_bpage *
  *
#ISCELL
  mstr_standard offpage *
  page115_i106
#ISCELL
  mstr_standard offpage *
  page115_i107
#CELL
  mstr_discrete res *
  page115_i114
#ISCELL
  mstr_symbols gnd *
  page115_i115
#CELL
  mstr_discrete res *
  page115_i118
#CELL
  mstr_discrete res *
  page115_i119
#CELL
  mstr_discrete res *
  page115_i120
#CELL
  mstr_discrete res *
  page115_i121
#CELL
  mstr_discrete res *
  page115_i122
#CELL
  mstr_discrete res *
  page115_i123
#ISCELL
  mstr_standard offpage *
  page115_i124
#ISCELL
  mstr_standard offpage *
  page115_i125
#ISCELL
  mstr_standard offpage *
  page115_i126
#ISCELL
  mstr_standard offpage *
  page115_i127
#ISCELL
  mstr_standard offpage *
  page115_i128
#ISCELL
  mstr_standard offpage *
  page115_i129
#ISCELL
  mstr_standard offpage *
  page115_i130
#ISCELL
  mstr_standard offpage *
  page115_i131
#ISCELL
  mstr_standard offpage *
  page115_i132
#ISCELL
  mstr_standard offpage *
  page115_i133
#CELL
  mstr_u_proc lbg_core_qat_ext_d *
  page115_i74
#CELL
  mstr_discrete res *
  page115_i90
#ISCELL
  mstr_symbols gnd *
  page115_i91
